(kicad_pcb
	(version 20260206)
	(generator "pcbnew")
	(generator_version "10.0")
	(general
		(thickness 1.6)
		(legacy_teardrops no)
	)
	(paper "A4")
	(title_block
		(title "03242023_DA0F0TMBIJ0_F0T_Motherboard_J_brd_V01_OCP.brd")
		(comment 1 "Grand Teton / footprints 5775-5781 of 6105")
	)
	(layers
		(0 "F.Cu" signal "TOP")
		(4 "In1.Cu" signal "GND")
		(6 "In2.Cu" signal "IN1")
		(8 "In3.Cu" signal "GND1")
		(10 "In4.Cu" signal "IN2")
		(12 "In5.Cu" signal "GND2")
		(14 "In6.Cu" signal "IN3")
		(16 "In7.Cu" signal "GND3")
		(18 "In8.Cu" signal "VCC")
		(20 "In9.Cu" signal "VCC1")
		(22 "In10.Cu" signal "GND4")
		(24 "In11.Cu" signal "IN4")
		(26 "In12.Cu" signal "GND5")
		(28 "In13.Cu" signal "IN5")
		(30 "In14.Cu" signal "GND6")
		(32 "In15.Cu" signal "IN6")
		(34 "In16.Cu" signal "GND7")
		(2 "B.Cu" signal "BOTTOM")
		(9 "F.Adhes" user "F.Adhesive")
		(11 "B.Adhes" user "B.Adhesive")
		(13 "F.Paste" user "Package Geometry/Pastemask Top")
		(15 "B.Paste" user "Package Geometry/Pastemask Bottom")
		(5 "F.SilkS" user "Ref Des/Silkscreen Top")
		(7 "B.SilkS" user "Ref Des/Silkscreen Bottom")
		(1 "F.Mask" user "Board Geometry/Soldermask Top")
		(3 "B.Mask" user "Board Geometry/Soldermask Bottom")
		(17 "Dwgs.User" user "User.Drawings")
		(19 "Cmts.User" user "User.Comments")
		(21 "Eco1.User" user "User.Eco1")
		(23 "Eco2.User" user "User.Eco2")
		(25 "Edge.Cuts" user "Board Geometry/Outline")
		(27 "Margin" user)
		(31 "F.CrtYd" user "Package Geometry/Place Bound Top")
		(29 "B.CrtYd" user "Package Geometry/Place Bound Bottom")
		(35 "F.Fab" user "Ref Des/Assembly Top")
		(33 "B.Fab" user "Ref Des/Assembly Bottom")
	)
	(footprint ""
		(layer "B.Cu")
		(at 338.280502 -341.017606 -90)
		(property "Reference" "PC258_P0_6"
			(at 0 0 90)
			(layer "B.SilkS")
			(hide yes)
			(effects
				(font
					(size 1.27 1.27)
				)
				(justify mirror)
			)
		)
		(property "Value" ""
			(at 0 0 90)
			(layer "B.Fab")
			(effects
				(font
					(size 1.27 1.27)
				)
				(justify mirror)
			)
		)
		(duplicate_pad_numbers_are_jumpers no)
		(fp_line
			(start -1.524 0.762)
			(end 1.524 0.762)
			(stroke
				(width 0.1524)
				(type default)
			)
			(layer "B.SilkS")
		)
		(fp_line
			(start 1.524 0.762)
			(end 1.524 -0.762)
			(stroke
				(width 0.1524)
				(type default)
			)
			(layer "B.SilkS")
		)
		(fp_line
			(start -1.524 -0.762)
			(end -1.524 0.762)
			(stroke
				(width 0.1524)
				(type default)
			)
			(layer "B.SilkS")
		)
		(fp_line
			(start 1.524 -0.762)
			(end -1.524 -0.762)
			(stroke
				(width 0.1524)
				(type default)
			)
			(layer "B.SilkS")
		)
		(fp_line
			(start -1.1049 0.724916)
			(end -1.1049 -0.724916)
			(stroke
				(width 0.1)
				(type default)
			)
			(layer "B.Fab")
		)
		(fp_line
			(start 1.1049 0.724916)
			(end -1.1049 0.724916)
			(stroke
				(width 0.1)
				(type default)
			)
			(layer "B.Fab")
		)
		(fp_line
			(start -1.1049 -0.724916)
			(end 1.1049 -0.724916)
			(stroke
				(width 0.1)
				(type default)
			)
			(layer "B.Fab")
		)
		(fp_line
			(start 1.1049 -0.724916)
			(end 1.1049 0.724916)
			(stroke
				(width 0.1)
				(type default)
			)
			(layer "B.Fab")
		)
		(pad "1" smd rect
			(at 0.889 0 270)
			(size 1.016 1.27)
			(layers "B.Cu" "B.Mask" "B.Paste")
			(net "SW_P12V_PVCCIN_CPU0_FLT")
		)
		(pad "2" smd rect
			(at -0.889 0 270)
			(size 1.016 1.27)
			(layers "B.Cu" "B.Mask" "B.Paste")
			(net "GND")
		)
	)
	(footprint ""
		(layer "B.Cu")
		(at 367.824258 -241.11585 90)
		(property "Reference" "C515"
			(at 0 0 90)
			(layer "B.SilkS")
			(hide yes)
			(effects
				(font
					(size 1.27 1.27)
				)
				(justify mirror)
			)
		)
		(property "Value" ""
			(at 0 0 90)
			(layer "B.Fab")
			(effects
				(font
					(size 1.27 1.27)
				)
				(justify mirror)
			)
		)
		(duplicate_pad_numbers_are_jumpers no)
		(fp_line
			(start 1.524 -0.762)
			(end -1.524 -0.762)
			(stroke
				(width 0.1524)
				(type default)
			)
			(layer "B.SilkS")
		)
		(fp_line
			(start -1.524 -0.762)
			(end -1.524 0.762)
			(stroke
				(width 0.1524)
				(type default)
			)
			(layer "B.SilkS")
		)
		(fp_line
			(start 1.524 0.762)
			(end 1.524 -0.762)
			(stroke
				(width 0.1524)
				(type default)
			)
			(layer "B.SilkS")
		)
		(fp_line
			(start -1.524 0.762)
			(end 1.524 0.762)
			(stroke
				(width 0.1524)
				(type default)
			)
			(layer "B.SilkS")
		)
		(fp_line
			(start 1.1049 -0.724916)
			(end 1.1049 0.724916)
			(stroke
				(width 0.1)
				(type default)
			)
			(layer "B.Fab")
		)
		(fp_line
			(start -1.1049 -0.724916)
			(end 1.1049 -0.724916)
			(stroke
				(width 0.1)
				(type default)
			)
			(layer "B.Fab")
		)
		(fp_line
			(start 1.1049 0.724916)
			(end -1.1049 0.724916)
			(stroke
				(width 0.1)
				(type default)
			)
			(layer "B.Fab")
		)
		(fp_line
			(start -1.1049 0.724916)
			(end -1.1049 -0.724916)
			(stroke
				(width 0.1)
				(type default)
			)
			(layer "B.Fab")
		)
		(pad "1" smd rect
			(at 0.889 0 90)
			(size 1.016 1.27)
			(layers "B.Cu" "B.Mask" "B.Paste")
			(net "PVCCD_HV_CPU0")
		)
		(pad "2" smd rect
			(at -0.889 0 90)
			(size 1.016 1.27)
			(layers "B.Cu" "B.Mask" "B.Paste")
			(net "GND")
		)
	)
	(footprint ""
		(layer "B.Cu")
		(at 301.356014 -321.549776 -90)
		(property "Reference" "C4"
			(at 0 0 90)
			(layer "B.SilkS")
			(hide yes)
			(effects
				(font
					(size 1.27 1.27)
				)
				(justify mirror)
			)
		)
		(property "Value" ""
			(at 0 0 90)
			(layer "B.Fab")
			(effects
				(font
					(size 1.27 1.27)
				)
				(justify mirror)
			)
		)
		(duplicate_pad_numbers_are_jumpers no)
		(fp_line
			(start -1.524 0.762)
			(end 1.524 0.762)
			(stroke
				(width 0.1524)
				(type default)
			)
			(layer "B.SilkS")
		)
		(fp_line
			(start 1.524 0.762)
			(end 1.524 -0.762)
			(stroke
				(width 0.1524)
				(type default)
			)
			(layer "B.SilkS")
		)
		(fp_line
			(start -1.524 -0.762)
			(end -1.524 0.762)
			(stroke
				(width 0.1524)
				(type default)
			)
			(layer "B.SilkS")
		)
		(fp_line
			(start 1.524 -0.762)
			(end -1.524 -0.762)
			(stroke
				(width 0.1524)
				(type default)
			)
			(layer "B.SilkS")
		)
		(fp_line
			(start -1.1049 0.724916)
			(end -1.1049 -0.724916)
			(stroke
				(width 0.1)
				(type default)
			)
			(layer "B.Fab")
		)
		(fp_line
			(start 1.1049 0.724916)
			(end -1.1049 0.724916)
			(stroke
				(width 0.1)
				(type default)
			)
			(layer "B.Fab")
		)
		(fp_line
			(start -1.1049 -0.724916)
			(end 1.1049 -0.724916)
			(stroke
				(width 0.1)
				(type default)
			)
			(layer "B.Fab")
		)
		(fp_line
			(start 1.1049 -0.724916)
			(end 1.1049 0.724916)
			(stroke
				(width 0.1)
				(type default)
			)
			(layer "B.Fab")
		)
		(pad "1" smd rect
			(at 0.889 0 270)
			(size 1.016 1.27)
			(layers "B.Cu" "B.Mask" "B.Paste")
			(net "P12V_S3_AUX_CPU0_NVDIMM")
		)
		(pad "2" smd rect
			(at -0.889 0 270)
			(size 1.016 1.27)
			(layers "B.Cu" "B.Mask" "B.Paste")
			(net "GND")
		)
	)
	(footprint ""
		(layer "B.Cu")
		(at 320.039492 -186.440318 90)
		(property "Reference" "R4390"
			(at 0 0 90)
			(layer "B.SilkS")
			(hide yes)
			(effects
				(font
					(size 1.27 1.27)
				)
				(justify mirror)
			)
		)
		(property "Value" ""
			(at 0 0 90)
			(layer "B.Fab")
			(effects
				(font
					(size 1.27 1.27)
				)
				(justify mirror)
			)
		)
		(duplicate_pad_numbers_are_jumpers no)
		(fp_line
			(start 0.7874 -0.4064)
			(end -0.7874 -0.4064)
			(stroke
				(width 0.1524)
				(type default)
			)
			(layer "B.SilkS")
		)
		(fp_line
			(start -0.7874 -0.4064)
			(end -0.7874 0.4064)
			(stroke
				(width 0.1524)
				(type default)
			)
			(layer "B.SilkS")
		)
		(fp_line
			(start 0.7874 0.4064)
			(end 0.7874 -0.4064)
			(stroke
				(width 0.1524)
				(type default)
			)
			(layer "B.SilkS")
		)
		(fp_line
			(start -0.7874 0.4064)
			(end 0.7874 0.4064)
			(stroke
				(width 0.1524)
				(type default)
			)
			(layer "B.SilkS")
		)
		(fp_line
			(start 0.67945 -0.305054)
			(end 0.12065 -0.305054)
			(stroke
				(width 0.1)
				(type default)
			)
			(layer "B.Fab")
		)
		(fp_line
			(start 0.12065 -0.305054)
			(end 0.12065 -0.2794)
			(stroke
				(width 0.1)
				(type default)
			)
			(layer "B.Fab")
		)
		(fp_line
			(start -0.12065 -0.3048)
			(end -0.67945 -0.3048)
			(stroke
				(width 0.1)
				(type default)
			)
			(layer "B.Fab")
		)
		(fp_line
			(start -0.67945 -0.3048)
			(end -0.67945 0.3048)
			(stroke
				(width 0.1)
				(type default)
			)
			(layer "B.Fab")
		)
		(fp_line
			(start 0.12065 -0.2794)
			(end -0.12065 -0.2794)
			(stroke
				(width 0.1)
				(type default)
			)
			(layer "B.Fab")
		)
		(fp_line
			(start -0.12065 -0.2794)
			(end -0.12065 -0.3048)
			(stroke
				(width 0.1)
				(type default)
			)
			(layer "B.Fab")
		)
		(fp_line
			(start 0.12065 0.2794)
			(end 0.12065 0.3048)
			(stroke
				(width 0.1)
				(type default)
			)
			(layer "B.Fab")
		)
		(fp_line
			(start -0.120396 0.2794)
			(end 0.12065 0.2794)
			(stroke
				(width 0.1)
				(type default)
			)
			(layer "B.Fab")
		)
		(fp_line
			(start 0.67945 0.3048)
			(end 0.67945 -0.305054)
			(stroke
				(width 0.1)
				(type default)
			)
			(layer "B.Fab")
		)
		(fp_line
			(start 0.12065 0.3048)
			(end 0.67945 0.3048)
			(stroke
				(width 0.1)
				(type default)
			)
			(layer "B.Fab")
		)
		(fp_line
			(start -0.120396 0.3048)
			(end -0.120396 0.2794)
			(stroke
				(width 0.1)
				(type default)
			)
			(layer "B.Fab")
		)
		(fp_line
			(start -0.67945 0.3048)
			(end -0.120396 0.3048)
			(stroke
				(width 0.1)
				(type default)
			)
			(layer "B.Fab")
		)
		(pad "1" smd circle
			(at 0.40005 0 270)
			(size 0 0)
			(layers "B.Cu" "B.Mask" "B.Paste")
			(net "PVNN_TERM_CPU0")
		)
		(pad "2" smd circle
			(at -0.40005 0 270)
			(size 0 0)
			(layers "B.Cu" "B.Mask" "B.Paste")
			(net "H_CPU_ERR0_LVC1_R_N")
		)
	)
	(footprint ""
		(layer "B.Cu")
		(at 145.18132 -13.762228 90)
		(property "Reference" "R1816"
			(at 0 0 90)
			(layer "B.SilkS")
			(hide yes)
			(effects
				(font
					(size 1.27 1.27)
				)
				(justify mirror)
			)
		)
		(property "Value" ""
			(at 0 0 90)
			(layer "B.Fab")
			(effects
				(font
					(size 1.27 1.27)
				)
				(justify mirror)
			)
		)
		(duplicate_pad_numbers_are_jumpers no)
		(fp_line
			(start 0.7874 -0.4064)
			(end -0.7874 -0.4064)
			(stroke
				(width 0.1524)
				(type default)
			)
			(layer "B.SilkS")
		)
		(fp_line
			(start -0.7874 -0.4064)
			(end -0.7874 0.4064)
			(stroke
				(width 0.1524)
				(type default)
			)
			(layer "B.SilkS")
		)
		(fp_line
			(start 0.7874 0.4064)
			(end 0.7874 -0.4064)
			(stroke
				(width 0.1524)
				(type default)
			)
			(layer "B.SilkS")
		)
		(fp_line
			(start -0.7874 0.4064)
			(end 0.7874 0.4064)
			(stroke
				(width 0.1524)
				(type default)
			)
			(layer "B.SilkS")
		)
		(fp_line
			(start 0.67945 -0.305054)
			(end 0.12065 -0.305054)
			(stroke
				(width 0.1)
				(type default)
			)
			(layer "B.Fab")
		)
		(fp_line
			(start 0.12065 -0.305054)
			(end 0.12065 -0.2794)
			(stroke
				(width 0.1)
				(type default)
			)
			(layer "B.Fab")
		)
		(fp_line
			(start -0.12065 -0.3048)
			(end -0.67945 -0.3048)
			(stroke
				(width 0.1)
				(type default)
			)
			(layer "B.Fab")
		)
		(fp_line
			(start -0.67945 -0.3048)
			(end -0.67945 0.3048)
			(stroke
				(width 0.1)
				(type default)
			)
			(layer "B.Fab")
		)
		(fp_line
			(start 0.12065 -0.2794)
			(end -0.12065 -0.2794)
			(stroke
				(width 0.1)
				(type default)
			)
			(layer "B.Fab")
		)
		(fp_line
			(start -0.12065 -0.2794)
			(end -0.12065 -0.3048)
			(stroke
				(width 0.1)
				(type default)
			)
			(layer "B.Fab")
		)
		(fp_line
			(start 0.12065 0.2794)
			(end 0.12065 0.3048)
			(stroke
				(width 0.1)
				(type default)
			)
			(layer "B.Fab")
		)
		(fp_line
			(start -0.120396 0.2794)
			(end 0.12065 0.2794)
			(stroke
				(width 0.1)
				(type default)
			)
			(layer "B.Fab")
		)
		(fp_line
			(start 0.67945 0.3048)
			(end 0.67945 -0.305054)
			(stroke
				(width 0.1)
				(type default)
			)
			(layer "B.Fab")
		)
		(fp_line
			(start 0.12065 0.3048)
			(end 0.67945 0.3048)
			(stroke
				(width 0.1)
				(type default)
			)
			(layer "B.Fab")
		)
		(fp_line
			(start -0.120396 0.3048)
			(end -0.120396 0.2794)
			(stroke
				(width 0.1)
				(type default)
			)
			(layer "B.Fab")
		)
		(fp_line
			(start -0.67945 0.3048)
			(end -0.120396 0.3048)
			(stroke
				(width 0.1)
				(type default)
			)
			(layer "B.Fab")
		)
		(pad "1" smd circle
			(at 0.40005 0 270)
			(size 0 0)
			(layers "B.Cu" "B.Mask" "B.Paste")
			(net "PWRGD_PS_PWROK")
		)
		(pad "2" smd circle
			(at -0.40005 0 270)
			(size 0 0)
			(layers "B.Cu" "B.Mask" "B.Paste")
			(net "PWRGD_PS_PWROK_R")
		)
	)
	(footprint ""
		(layer "B.Cu")
		(at 446.941448 -181.977792 180)
		(property "Reference" "C1364"
			(at 0 0 0)
			(layer "B.SilkS")
			(hide yes)
			(effects
				(font
					(size 1.27 1.27)
				)
				(justify mirror)
			)
		)
		(property "Value" ""
			(at 0 0 0)
			(layer "B.Fab")
			(effects
				(font
					(size 1.27 1.27)
				)
				(justify mirror)
			)
		)
		(duplicate_pad_numbers_are_jumpers no)
		(fp_line
			(start 0.7874 0.4064)
			(end 0.7874 -0.4064)
			(stroke
				(width 0.1524)
				(type default)
			)
			(layer "B.SilkS")
		)
		(fp_line
			(start 0.7874 -0.4064)
			(end -0.7874 -0.4064)
			(stroke
				(width 0.1524)
				(type default)
			)
			(layer "B.SilkS")
		)
		(fp_line
			(start -0.7874 0.4064)
			(end 0.7874 0.4064)
			(stroke
				(width 0.1524)
				(type default)
			)
			(layer "B.SilkS")
		)
		(fp_line
			(start -0.7874 -0.4064)
			(end -0.7874 0.4064)
			(stroke
				(width 0.1524)
				(type default)
			)
			(layer "B.SilkS")
		)
		(fp_line
			(start 0.67945 0.3048)
			(end 0.67945 -0.305054)
			(stroke
				(width 0.1)
				(type default)
			)
			(layer "B.Fab")
		)
		(fp_line
			(start 0.67945 -0.305054)
			(end 0.12065 -0.305054)
			(stroke
				(width 0.1)
				(type default)
			)
			(layer "B.Fab")
		)
		(fp_line
			(start 0.12065 0.3048)
			(end 0.67945 0.3048)
			(stroke
				(width 0.1)
				(type default)
			)
			(layer "B.Fab")
		)
		(fp_line
			(start 0.12065 0.2794)
			(end 0.12065 0.3048)
			(stroke
				(width 0.1)
				(type default)
			)
			(layer "B.Fab")
		)
		(fp_line
			(start 0.12065 -0.2794)
			(end -0.12065 -0.2794)
			(stroke
				(width 0.1)
				(type default)
			)
			(layer "B.Fab")
		)
		(fp_line
			(start 0.12065 -0.305054)
			(end 0.12065 -0.2794)
			(stroke
				(width 0.1)
				(type default)
			)
			(layer "B.Fab")
		)
		(fp_line
			(start -0.120396 0.3048)
			(end -0.120396 0.2794)
			(stroke
				(width 0.1)
				(type default)
			)
			(layer "B.Fab")
		)
		(fp_line
			(start -0.120396 0.2794)
			(end 0.12065 0.2794)
			(stroke
				(width 0.1)
				(type default)
			)
			(layer "B.Fab")
		)
		(fp_line
			(start -0.12065 -0.2794)
			(end -0.12065 -0.3048)
			(stroke
				(width 0.1)
				(type default)
			)
			(layer "B.Fab")
		)
		(fp_line
			(start -0.12065 -0.3048)
			(end -0.67945 -0.3048)
			(stroke
				(width 0.1)
				(type default)
			)
			(layer "B.Fab")
		)
		(fp_line
			(start -0.67945 0.3048)
			(end -0.120396 0.3048)
			(stroke
				(width 0.1)
				(type default)
			)
			(layer "B.Fab")
		)
		(fp_line
			(start -0.67945 -0.3048)
			(end -0.67945 0.3048)
			(stroke
				(width 0.1)
				(type default)
			)
			(layer "B.Fab")
		)
		(pad "1" smd circle
			(at 0.40005 0)
			(size 0 0)
			(layers "B.Cu" "B.Mask" "B.Paste")
			(net "PVNN_MAIN_CPU0")
		)
		(pad "2" smd circle
			(at -0.40005 0)
			(size 0 0)
			(layers "B.Cu" "B.Mask" "B.Paste")
			(net "GND")
		)
	)
	(footprint ""
		(layer "B.Cu")
		(at 320.776092 -37.442902 45)
		(property "Reference" "R1402"
			(at 0 0 45)
			(layer "B.SilkS")
			(hide yes)
			(effects
				(font
					(size 1.27 1.27)
				)
				(justify mirror)
			)
		)
		(property "Value" ""
			(at 0 0 45)
			(layer "B.Fab")
			(effects
				(font
					(size 1.27 1.27)
				)
				(justify mirror)
			)
		)
		(duplicate_pad_numbers_are_jumpers no)
		(fp_line
			(start -0.787389 -0.406267)
			(end -0.787389 0.406267)
			(stroke
				(width 0.1524)
				(type default)
			)
			(layer "B.SilkS")
		)
		(fp_line
			(start -0.787389 0.406267)
			(end 0.787389 0.406267)
			(stroke
				(width 0.1524)
				(type default)
			)
			(layer "B.SilkS")
		)
		(fp_line
			(start 0.787389 -0.406267)
			(end -0.787389 -0.406267)
			(stroke
				(width 0.1524)
				(type default)
			)
			(layer "B.SilkS")
		)
		(fp_line
			(start 0.787389 0.406267)
			(end 0.787389 -0.406267)
			(stroke
				(width 0.1524)
				(type default)
			)
			(layer "B.SilkS")
		)
		(fp_line
			(start -0.679446 -0.30479)
			(end -0.679446 0.30479)
			(stroke
				(width 0.1)
				(type default)
			)
			(layer "B.Fab")
		)
		(fp_line
			(start -0.120515 -0.30479)
			(end -0.679446 -0.30479)
			(stroke
				(width 0.1)
				(type default)
			)
			(layer "B.Fab")
		)
		(fp_line
			(start -0.120695 -0.279466)
			(end -0.120515 -0.30479)
			(stroke
				(width 0.1)
				(type default)
			)
			(layer "B.Fab")
		)
		(fp_line
			(start -0.679446 0.30479)
			(end -0.120515 0.30479)
			(stroke
				(width 0.1)
				(type default)
			)
			(layer "B.Fab")
		)
		(fp_line
			(start 0.120695 -0.304969)
			(end 0.120695 -0.279466)
			(stroke
				(width 0.1)
				(type default)
			)
			(layer "B.Fab")
		)
		(fp_line
			(start 0.120695 -0.279466)
			(end -0.120695 -0.279466)
			(stroke
				(width 0.1)
				(type default)
			)
			(layer "B.Fab")
		)
		(fp_line
			(start -0.120335 0.279466)
			(end 0.120695 0.279466)
			(stroke
				(width 0.1)
				(type default)
			)
			(layer "B.Fab")
		)
		(fp_line
			(start -0.120515 0.30479)
			(end -0.120335 0.279466)
			(stroke
				(width 0.1)
				(type default)
			)
			(layer "B.Fab")
		)
		(fp_line
			(start 0.679446 -0.305149)
			(end 0.120695 -0.304969)
			(stroke
				(width 0.1)
				(type default)
			)
			(layer "B.Fab")
		)
		(fp_line
			(start 0.120695 0.279466)
			(end 0.120515 0.30479)
			(stroke
				(width 0.1)
				(type default)
			)
			(layer "B.Fab")
		)
		(fp_line
			(start 0.120515 0.30479)
			(end 0.679446 0.30479)
			(stroke
				(width 0.1)
				(type default)
			)
			(layer "B.Fab")
		)
		(fp_line
			(start 0.679446 0.30479)
			(end 0.679446 -0.305149)
			(stroke
				(width 0.1)
				(type default)
			)
			(layer "B.Fab")
		)
		(pad "1" smd circle
			(at 0.40005 0 225)
			(size 0 0)
			(layers "B.Cu" "B.Mask" "B.Paste")
			(net "PWRGD_SYS_PWROK")
		)
		(pad "2" smd circle
			(at -0.40005 0 225)
			(size 0 0)
			(layers "B.Cu" "B.Mask" "B.Paste")
			(net "GND")
		)
	)
)
